# SCM (Grand Teton) — schematic netlist excerpt (pin names and nets, part order shuffled) for the footprints in the layout excerpt that follows; sources: Cadence DE-HDL packaged netlist, KiCad conversion of 12092022_DA0F0TMDCD0_F0T_Management_Board_D_brd_V3_OCP.brd

C116  Q_CAP  1UF 25V 10% X6S  pkg C0402  page 16 : A = P1V8_AUX ; B = GND
R219  Q_RES  100K 1% EMPTY  pkg 0402LF  page 29 : A = DEBUG_PORT_UART_TX ; B = GND

(kicad_pcb
	(version 20260206)
	(generator "pcbnew")
	(generator_version "10.0")
	(general
		(thickness 1.6)
		(legacy_teardrops no)
	)
	(paper "A4")
	(title_block
		(title "12092022_DA0F0TMDCD0_F0T_Management_Board_D_brd_V3_OCP.brd")
		(comment 1 "Grand Teton / footprints 839-840 of 1440")
	)
	(layers
		(0 "F.Cu" signal "TOP")
		(4 "In1.Cu" signal "GND")
		(6 "In2.Cu" signal "IN1")
		(8 "In3.Cu" signal "GND1")
		(10 "In4.Cu" signal "IN2")
		(12 "In5.Cu" signal "VCC")
		(14 "In6.Cu" signal "VCC1")
		(16 "In7.Cu" signal "IN3")
		(18 "In8.Cu" signal "GND2")
		(20 "In9.Cu" signal "IN4")
		(22 "In10.Cu" signal "GND3")
		(2 "B.Cu" signal "BOTTOM")
		(9 "F.Adhes" user "F.Adhesive")
		(11 "B.Adhes" user "B.Adhesive")
		(13 "F.Paste" user "Package Geometry/Pastemask Top")
		(15 "B.Paste" user "Package Geometry/Pastemask Bottom")
		(5 "F.SilkS" user "Ref Des/Silkscreen Top")
		(7 "B.SilkS" user "Ref Des/Silkscreen Bottom")
		(1 "F.Mask" user "Board Geometry/Soldermask Top")
		(3 "B.Mask" user "Board Geometry/Soldermask Bottom")
		(17 "Dwgs.User" user "User.Drawings")
		(19 "Cmts.User" user "User.Comments")
		(21 "Eco1.User" user "User.Eco1")
		(23 "Eco2.User" user "User.Eco2")
		(25 "Edge.Cuts" user "Board Geometry/Outline")
		(27 "Margin" user)
		(31 "F.CrtYd" user "Package Geometry/Place Bound Top")
		(29 "B.CrtYd" user "Package Geometry/Place Bound Bottom")
		(35 "F.Fab" user "Ref Des/Assembly Top")
		(33 "B.Fab" user "Ref Des/Assembly Bottom")
	)
	(footprint ""
		(layer "B.Cu")
		(at 57.785 -24.13 -90)
		(property "Reference" "R219"
			(at 0 0 90)
			(layer "B.SilkS")
			(hide yes)
			(effects
				(font
					(size 1.27 1.27)
				)
				(justify mirror)
			)
		)
		(property "Value" ""
			(at 0 0 90)
			(layer "B.Fab")
			(effects
				(font
					(size 1.27 1.27)
				)
				(justify mirror)
			)
		)
		(duplicate_pad_numbers_are_jumpers no)
		(fp_line
			(start -0.7874 0.4064)
			(end 0.7874 0.4064)
			(stroke
				(width 0.1524)
				(type default)
			)
			(layer "B.SilkS")
		)
		(fp_line
			(start 0.7874 0.4064)
			(end 0.7874 -0.4064)
			(stroke
				(width 0.1524)
				(type default)
			)
			(layer "B.SilkS")
		)
		(fp_line
			(start -0.7874 -0.4064)
			(end -0.7874 0.4064)
			(stroke
				(width 0.1524)
				(type default)
			)
			(layer "B.SilkS")
		)
		(fp_line
			(start 0.7874 -0.4064)
			(end -0.7874 -0.4064)
			(stroke
				(width 0.1524)
				(type default)
			)
			(layer "B.SilkS")
		)
		(fp_line
			(start -0.67945 0.3048)
			(end -0.120396 0.3048)
			(stroke
				(width 0.1)
				(type default)
			)
			(layer "B.Fab")
		)
		(fp_line
			(start -0.120396 0.3048)
			(end -0.120396 0.2794)
			(stroke
				(width 0.1)
				(type default)
			)
			(layer "B.Fab")
		)
		(fp_line
			(start 0.12065 0.3048)
			(end 0.67945 0.3048)
			(stroke
				(width 0.1)
				(type default)
			)
			(layer "B.Fab")
		)
		(fp_line
			(start 0.67945 0.3048)
			(end 0.67945 -0.305054)
			(stroke
				(width 0.1)
				(type default)
			)
			(layer "B.Fab")
		)
		(fp_line
			(start -0.120396 0.2794)
			(end 0.12065 0.2794)
			(stroke
				(width 0.1)
				(type default)
			)
			(layer "B.Fab")
		)
		(fp_line
			(start 0.12065 0.2794)
			(end 0.12065 0.3048)
			(stroke
				(width 0.1)
				(type default)
			)
			(layer "B.Fab")
		)
		(fp_line
			(start -0.12065 -0.2794)
			(end -0.12065 -0.3048)
			(stroke
				(width 0.1)
				(type default)
			)
			(layer "B.Fab")
		)
		(fp_line
			(start 0.12065 -0.2794)
			(end -0.12065 -0.2794)
			(stroke
				(width 0.1)
				(type default)
			)
			(layer "B.Fab")
		)
		(fp_line
			(start -0.67945 -0.3048)
			(end -0.67945 0.3048)
			(stroke
				(width 0.1)
				(type default)
			)
			(layer "B.Fab")
		)
		(fp_line
			(start -0.12065 -0.3048)
			(end -0.67945 -0.3048)
			(stroke
				(width 0.1)
				(type default)
			)
			(layer "B.Fab")
		)
		(fp_line
			(start 0.12065 -0.305054)
			(end 0.12065 -0.2794)
			(stroke
				(width 0.1)
				(type default)
			)
			(layer "B.Fab")
		)
		(fp_line
			(start 0.67945 -0.305054)
			(end 0.12065 -0.305054)
			(stroke
				(width 0.1)
				(type default)
			)
			(layer "B.Fab")
		)
		(pad "1" smd circle
			(at 0.40005 0 90)
			(size 0 0)
			(layers "B.Cu" "B.Mask" "B.Paste")
			(net "DEBUG_PORT_UART_TX")
		)
		(pad "2" smd circle
			(at -0.40005 0 90)
			(size 0 0)
			(layers "B.Cu" "B.Mask" "B.Paste")
			(net "GND")
		)
	)
	(footprint ""
		(layer "B.Cu")
		(at 55.08117 -47.85741 -90)
		(property "Reference" "C116"
			(at 0 0 90)
			(layer "B.SilkS")
			(hide yes)
			(effects
				(font
					(size 1.27 1.27)
				)
				(justify mirror)
			)
		)
		(property "Value" ""
			(at 0 0 90)
			(layer "B.Fab")
			(effects
				(font
					(size 1.27 1.27)
				)
				(justify mirror)
			)
		)
		(duplicate_pad_numbers_are_jumpers no)
		(fp_line
			(start -0.7874 0.4064)
			(end 0.7874 0.4064)
			(stroke
				(width 0.1524)
				(type default)
			)
			(layer "B.SilkS")
		)
		(fp_line
			(start 0.7874 0.4064)
			(end 0.7874 -0.4064)
			(stroke
				(width 0.1524)
				(type default)
			)
			(layer "B.SilkS")
		)
		(fp_line
			(start -0.7874 -0.4064)
			(end -0.7874 0.4064)
			(stroke
				(width 0.1524)
				(type default)
			)
			(layer "B.SilkS")
		)
		(fp_line
			(start 0.7874 -0.4064)
			(end -0.7874 -0.4064)
			(stroke
				(width 0.1524)
				(type default)
			)
			(layer "B.SilkS")
		)
		(fp_line
			(start -0.67945 0.3048)
			(end -0.120396 0.3048)
			(stroke
				(width 0.1)
				(type default)
			)
			(layer "B.Fab")
		)
		(fp_line
			(start -0.120396 0.3048)
			(end -0.120396 0.2794)
			(stroke
				(width 0.1)
				(type default)
			)
			(layer "B.Fab")
		)
		(fp_line
			(start 0.12065 0.3048)
			(end 0.67945 0.3048)
			(stroke
				(width 0.1)
				(type default)
			)
			(layer "B.Fab")
		)
		(fp_line
			(start 0.67945 0.3048)
			(end 0.67945 -0.305054)
			(stroke
				(width 0.1)
				(type default)
			)
			(layer "B.Fab")
		)
		(fp_line
			(start -0.120396 0.2794)
			(end 0.12065 0.2794)
			(stroke
				(width 0.1)
				(type default)
			)
			(layer "B.Fab")
		)
		(fp_line
			(start 0.12065 0.2794)
			(end 0.12065 0.3048)
			(stroke
				(width 0.1)
				(type default)
			)
			(layer "B.Fab")
		)
		(fp_line
			(start -0.12065 -0.2794)
			(end -0.12065 -0.3048)
			(stroke
				(width 0.1)
				(type default)
			)
			(layer "B.Fab")
		)
		(fp_line
			(start 0.12065 -0.2794)
			(end -0.12065 -0.2794)
			(stroke
				(width 0.1)
				(type default)
			)
			(layer "B.Fab")
		)
		(fp_line
			(start -0.67945 -0.3048)
			(end -0.67945 0.3048)
			(stroke
				(width 0.1)
				(type default)
			)
			(layer "B.Fab")
		)
		(fp_line
			(start -0.12065 -0.3048)
			(end -0.67945 -0.3048)
			(stroke
				(width 0.1)
				(type default)
			)
			(layer "B.Fab")
		)
		(fp_line
			(start 0.12065 -0.305054)
			(end 0.12065 -0.2794)
			(stroke
				(width 0.1)
				(type default)
			)
			(layer "B.Fab")
		)
		(fp_line
			(start 0.67945 -0.305054)
			(end 0.12065 -0.305054)
			(stroke
				(width 0.1)
				(type default)
			)
			(layer "B.Fab")
		)
		(pad "1" smd circle
			(at 0.40005 0 90)
			(size 0 0)
			(layers "B.Cu" "B.Mask" "B.Paste")
			(net "P1V8_AUX")
		)
		(pad "2" smd circle
			(at -0.40005 0 90)
			(size 0 0)
			(layers "B.Cu" "B.Mask" "B.Paste")
			(net "GND")
		)
	)
)
